(kicad_pcb
	(version 20241229)
	(generator "pcbnew")
	(generator_version "9.0")
	(general
		(thickness 1.711)
		(legacy_teardrops no)
	)
	(paper "A4")
	(title_block
		(title "Antmicro Baseboard for Jetson AGX Thor")
		(date "2026-02-18")
		(rev "1.1.0")
		(company "Antmicro Ltd")
		(comment 1 "www.antmicro.com")
		(comment 9 "footprints 292-296 of 1170")
	)
	(layers
		(0 "F.Cu" signal)
		(4 "In1.Cu" signal)
		(6 "In2.Cu" signal)
		(8 "In3.Cu" signal)
		(10 "In4.Cu" jumper)
		(12 "In5.Cu" signal)
		(14 "In6.Cu" signal)
		(16 "In7.Cu" signal)
		(18 "In8.Cu" signal)
		(2 "B.Cu" signal)
		(9 "F.Adhes" user "F.Adhesive")
		(11 "B.Adhes" user "B.Adhesive")
		(13 "F.Paste" user)
		(15 "B.Paste" user)
		(5 "F.SilkS" user "F.Silkscreen")
		(7 "B.SilkS" user "B.Silkscreen")
		(1 "F.Mask" user)
		(3 "B.Mask" user)
		(17 "Dwgs.User" user "User.Drawings")
		(19 "Cmts.User" user "User.Comments")
		(21 "Eco1.User" user "User.Eco1")
		(23 "Eco2.User" user "User.Eco2")
		(25 "Edge.Cuts" user)
		(27 "Margin" user)
		(31 "F.CrtYd" user "F.Courtyard")
		(29 "B.CrtYd" user "B.Courtyard")
		(35 "F.Fab" user)
		(33 "B.Fab" user)
	)
	(footprint "antmicro-footprints:C_0603_1608Metric_EIA"
		(layer "F.Cu")
		(at 142.4 128.15 -90)
		(descr "Capacitor SMD 0603, IPC-7351 Density Level A")
		(tags "Capacitor 0603")
		(property "Reference" "C31"
			(at -3.5 0.3 90)
			(layer "F.SilkS")
			(effects
				(font
					(size 0.7 0.7)
					(thickness 0.15)
				)
				(justify right top)
			)
		)
		(property "Value" "C_22u_16V_0603"
			(at -1.42757 1.770288 90)
			(layer "F.Fab")
			(effects
				(font
					(size 0.7 0.7)
					(thickness 0.15)
				)
				(justify right top)
			)
		)
		(property "Datasheet" "https://product.samsungsem.com/mlcc/CL10A226MO7JZN.do"
			(at 0 0 90)
			(layer "F.Fab")
			(hide yes)
			(effects
				(font
					(size 1.27 1.27)
					(thickness 0.15)
				)
			)
		)
		(property "Description" "SMD Multilayer Ceramic Capacitor"
			(at 0 0 90)
			(layer "F.Fab")
			(hide yes)
			(effects
				(font
					(size 1.27 1.27)
					(thickness 0.15)
				)
			)
		)
		(property "MPN" "CL10A226MO7JZNC"
			(at 0 0 270)
			(unlocked yes)
			(layer "F.Fab")
			(hide yes)
			(effects
				(font
					(size 1 1)
					(thickness 0.15)
				)
			)
		)
		(property "Manufacturer" "Samsung Electro-Mechanics"
			(at 0 0 270)
			(unlocked yes)
			(layer "F.Fab")
			(hide yes)
			(effects
				(font
					(size 1 1)
					(thickness 0.15)
				)
			)
		)
		(property "License" "Apache-2.0"
			(at 0 0 270)
			(unlocked yes)
			(layer "F.Fab")
			(hide yes)
			(effects
				(font
					(size 1 1)
					(thickness 0.15)
				)
			)
		)
		(property "Author" "Antmicro"
			(at 0 0 270)
			(unlocked yes)
			(layer "F.Fab")
			(hide yes)
			(effects
				(font
					(size 1 1)
					(thickness 0.15)
				)
			)
		)
		(property "Val" "22u"
			(at 0 0 270)
			(unlocked yes)
			(layer "F.Fab")
			(hide yes)
			(effects
				(font
					(size 1 1)
					(thickness 0.15)
				)
			)
		)
		(property "Voltage" "16V"
			(at 0 0 270)
			(unlocked yes)
			(layer "F.Fab")
			(hide yes)
			(effects
				(font
					(size 1 1)
					(thickness 0.15)
				)
			)
		)
		(property "Dielectric" ""
			(at 0 0 270)
			(unlocked yes)
			(layer "F.Fab")
			(hide yes)
			(effects
				(font
					(size 1 1)
					(thickness 0.15)
				)
			)
		)
		(property "Public" "False"
			(at 0 0 270)
			(unlocked yes)
			(layer "F.Fab")
			(hide yes)
			(effects
				(font
					(size 1 1)
					(thickness 0.15)
				)
			)
		)
		(component_classes
			(class "DCDC_1V8")
		)
		(sheetname "/DCDC/")
		(sheetfile "dcdc.kicad_sch")
		(attr smd)
		(fp_line
			(start -0.15 0.55)
			(end 0.15 0.55)
			(stroke
				(width 0.15)
				(type solid)
			)
			(layer "F.SilkS")
		)
		(fp_line
			(start -0.15 -0.55)
			(end 0.15 -0.55)
			(stroke
				(width 0.15)
				(type solid)
			)
			(layer "F.SilkS")
		)
		(fp_rect
			(start -1.25 -0.65)
			(end 1.25 0.65)
			(stroke
				(width 0.05)
				(type solid)
			)
			(fill no)
			(layer "F.CrtYd")
		)
		(fp_rect
			(start -0.8 -0.45)
			(end 0.8 0.45)
			(stroke
				(width 0.15)
				(type solid)
			)
			(fill no)
			(layer "F.Fab")
		)
		(fp_text user "${REFERENCE}"
			(at -1.682 3.895 90)
			(layer "F.Fab")
			(effects
				(font
					(size 0.7 0.7)
					(thickness 0.15)
				)
				(justify right top)
			)
		)
		(fp_text user "License: Apache-2.0"
			(at -1.682 5.895 90)
			(layer "F.Fab")
			(effects
				(font
					(size 0.7 0.7)
					(thickness 0.15)
				)
				(justify right top)
			)
		)
		(fp_text user "Author: Antmicro"
			(at -1.682 4.894 90)
			(layer "F.Fab")
			(effects
				(font
					(size 0.7 0.7)
					(thickness 0.15)
				)
				(justify right top)
			)
		)
		(pad "1" smd roundrect
			(at -0.7 0 270)
			(size 0.8 1.1)
			(layers "F.Cu" "F.Mask" "F.Paste")
			(roundrect_rratio 0.2)
			(net 1 "GND")
			(pintype "passive")
		)
		(pad "2" smd roundrect
			(at 0.7 0 270)
			(size 0.8 1.1)
			(layers "F.Cu" "F.Mask" "F.Paste")
			(roundrect_rratio 0.2)
			(net 5 "+5V")
			(pintype "passive")
		)
	)
	(footprint "antmicro-footprints:C_0402_1005Metric"
		(layer "F.Cu")
		(at 211 105.275)
		(descr "Capacitor SMD 0402")
		(tags "capacitor SMD 0402")
		(property "Reference" "C154"
			(at -3.77 0.4 0)
			(layer "F.SilkS")
			(effects
				(font
					(size 0.7 0.7)
					(thickness 0.15)
				)
				(justify left bottom)
			)
		)
		(property "Value" "C_100n_0402"
			(at -1.022927 2.155213 0)
			(layer "F.Fab")
			(effects
				(font
					(size 0.7 0.7)
					(thickness 0.15)
				)
				(justify left bottom)
			)
		)
		(property "Datasheet" "https://www.murata.com/products/productdetail?partno=GRM155R61H104KE14%23"
			(at 0 0 0)
			(layer "F.Fab")
			(hide yes)
			(effects
				(font
					(size 1.27 1.27)
					(thickness 0.15)
				)
			)
		)
		(property "Description" "SMD Multilayer Ceramic Capacitor, 0.1 µF, 50 V, 0402 [1005 Metric], ± 10%, X5R, GRM Series"
			(at 0 0 0)
			(layer "F.Fab")
			(hide yes)
			(effects
				(font
					(size 1.27 1.27)
					(thickness 0.15)
				)
			)
		)
		(property "Manufacturer" "Murata"
			(at 0 0 0)
			(unlocked yes)
			(layer "F.Fab")
			(hide yes)
			(effects
				(font
					(size 1 1)
					(thickness 0.15)
				)
			)
		)
		(property "MPN" "GRM155R61H104KE14D"
			(at 0 0 0)
			(unlocked yes)
			(layer "F.Fab")
			(hide yes)
			(effects
				(font
					(size 1 1)
					(thickness 0.15)
				)
			)
		)
		(property "Val" "100n"
			(at 0 0 0)
			(unlocked yes)
			(layer "F.Fab")
			(hide yes)
			(effects
				(font
					(size 1 1)
					(thickness 0.15)
				)
			)
		)
		(property "License" "Apache-2.0"
			(at 0 0 0)
			(unlocked yes)
			(layer "F.Fab")
			(hide yes)
			(effects
				(font
					(size 1 1)
					(thickness 0.15)
				)
			)
		)
		(property "Author" "Antmicro"
			(at 0 0 0)
			(unlocked yes)
			(layer "F.Fab")
			(hide yes)
			(effects
				(font
					(size 1 1)
					(thickness 0.15)
				)
			)
		)
		(property "Voltage" "50V"
			(at 0 0 0)
			(unlocked yes)
			(layer "F.Fab")
			(hide yes)
			(effects
				(font
					(size 1 1)
					(thickness 0.15)
				)
			)
		)
		(property "Dielectric" "X5R"
			(at 0 0 0)
			(unlocked yes)
			(layer "F.Fab")
			(hide yes)
			(effects
				(font
					(size 1 1)
					(thickness 0.15)
				)
			)
		)
		(sheetname "/Recovery USB/")
		(sheetfile "recovery_usb.kicad_sch")
		(attr smd)
		(fp_rect
			(start -0.925 -0.47)
			(end 0.925 0.47)
			(stroke
				(width 0.05)
				(type default)
			)
			(fill no)
			(layer "F.CrtYd")
		)
		(fp_line
			(start -0.494 -0.25)
			(end 0.504 -0.25)
			(stroke
				(width 0.15)
				(type solid)
			)
			(layer "F.Fab")
		)
		(fp_line
			(start -0.494 0.248)
			(end -0.494 -0.25)
			(stroke
				(width 0.15)
				(type solid)
			)
			(layer "F.Fab")
		)
		(fp_line
			(start 0.504 -0.25)
			(end 0.504 0.248)
			(stroke
				(width 0.15)
				(type solid)
			)
			(layer "F.Fab")
		)
		(fp_line
			(start 0.504 0.248)
			(end -0.494 0.248)
			(stroke
				(width 0.15)
				(type solid)
			)
			(layer "F.Fab")
		)
		(fp_text user "Author: Antmicro"
			(at -0.939 3.399 0)
			(layer "F.Fab")
			(effects
				(font
					(size 0.7 0.7)
					(thickness 0.15)
				)
				(justify left bottom)
			)
		)
		(fp_text user "${REFERENCE}"
			(at -0.939 4.599 0)
			(layer "F.Fab")
			(effects
				(font
					(size 0.7 0.7)
					(thickness 0.15)
				)
				(justify left bottom)
			)
		)
		(fp_text user "License: Apache-2.0"
			(at -0.939 5.799 0)
			(layer "F.Fab")
			(effects
				(font
					(size 0.7 0.7)
					(thickness 0.15)
				)
				(justify left bottom)
			)
		)
		(pad "1" smd roundrect
			(at -0.48 0)
			(size 0.59 0.64)
			(layers "F.Cu" "F.Mask" "F.Paste")
			(roundrect_rratio 0.25)
			(net 598 "/Recovery USB/USBSS0.RX+")
			(pintype "passive")
		)
		(pad "2" smd roundrect
			(at 0.48 0)
			(size 0.59 0.64)
			(layers "F.Cu" "F.Mask" "F.Paste")
			(roundrect_rratio 0.25)
			(net 1128 "/Recovery USB/USBSS_RX_N")
			(pintype "passive")
		)
	)
	(footprint "antmicro-footprints:C_0402_1005Metric"
		(layer "F.Cu")
		(at 218.8 131.8 180)
		(descr "Capacitor SMD 0402")
		(tags "capacitor SMD 0402")
		(property "Reference" "C83"
			(at -0.9 2.4 0)
			(layer "F.SilkS")
			(effects
				(font
					(size 0.7 0.7)
					(thickness 0.15)
				)
				(justify right top)
			)
		)
		(property "Value" "C_100n_0402"
			(at -1.022927 2.155213 0)
			(layer "F.Fab")
			(effects
				(font
					(size 0.7 0.7)
					(thickness 0.15)
				)
				(justify right top)
			)
		)
		(property "Datasheet" "https://www.murata.com/products/productdetail?partno=GRM155R61H104KE14%23"
			(at 0 0 0)
			(layer "F.Fab")
			(hide yes)
			(effects
				(font
					(size 1.27 1.27)
					(thickness 0.15)
				)
			)
		)
		(property "Description" "SMD Multilayer Ceramic Capacitor, 0.1 µF, 50 V, 0402 [1005 Metric], ± 10%, X5R, GRM Series"
			(at 0 0 0)
			(layer "F.Fab")
			(hide yes)
			(effects
				(font
					(size 1.27 1.27)
					(thickness 0.15)
				)
			)
		)
		(property "Manufacturer" "Murata"
			(at 0 0 180)
			(unlocked yes)
			(layer "F.Fab")
			(hide yes)
			(effects
				(font
					(size 1 1)
					(thickness 0.15)
				)
			)
		)
		(property "MPN" "GRM155R61H104KE14D"
			(at 0 0 180)
			(unlocked yes)
			(layer "F.Fab")
			(hide yes)
			(effects
				(font
					(size 1 1)
					(thickness 0.15)
				)
			)
		)
		(property "Val" "100n"
			(at 0 0 180)
			(unlocked yes)
			(layer "F.Fab")
			(hide yes)
			(effects
				(font
					(size 1 1)
					(thickness 0.15)
				)
			)
		)
		(property "License" "Apache-2.0"
			(at 0 0 180)
			(unlocked yes)
			(layer "F.Fab")
			(hide yes)
			(effects
				(font
					(size 1 1)
					(thickness 0.15)
				)
			)
		)
		(property "Author" "Antmicro"
			(at 0 0 180)
			(unlocked yes)
			(layer "F.Fab")
			(hide yes)
			(effects
				(font
					(size 1 1)
					(thickness 0.15)
				)
			)
		)
		(property "Voltage" "50V"
			(at 0 0 180)
			(unlocked yes)
			(layer "F.Fab")
			(hide yes)
			(effects
				(font
					(size 1 1)
					(thickness 0.15)
				)
			)
		)
		(property "Dielectric" "X5R"
			(at 0 0 180)
			(unlocked yes)
			(layer "F.Fab")
			(hide yes)
			(effects
				(font
					(size 1 1)
					(thickness 0.15)
				)
			)
		)
		(sheetname "/USB Hub/")
		(sheetfile "usb_hub.kicad_sch")
		(attr smd)
		(fp_rect
			(start -0.925 -0.47)
			(end 0.925 0.47)
			(stroke
				(width 0.05)
				(type default)
			)
			(fill no)
			(layer "F.CrtYd")
		)
		(fp_line
			(start 0.504 0.248)
			(end -0.494 0.248)
			(stroke
				(width 0.15)
				(type solid)
			)
			(layer "F.Fab")
		)
		(fp_line
			(start 0.504 -0.25)
			(end 0.504 0.248)
			(stroke
				(width 0.15)
				(type solid)
			)
			(layer "F.Fab")
		)
		(fp_line
			(start -0.494 0.248)
			(end -0.494 -0.25)
			(stroke
				(width 0.15)
				(type solid)
			)
			(layer "F.Fab")
		)
		(fp_line
			(start -0.494 -0.25)
			(end 0.504 -0.25)
			(stroke
				(width 0.15)
				(type solid)
			)
			(layer "F.Fab")
		)
		(fp_text user "License: Apache-2.0"
			(at -0.939 5.799 0)
			(layer "F.Fab")
			(effects
				(font
					(size 0.7 0.7)
					(thickness 0.15)
				)
				(justify right top)
			)
		)
		(fp_text user "${REFERENCE}"
			(at -0.939 4.599 0)
			(layer "F.Fab")
			(effects
				(font
					(size 0.7 0.7)
					(thickness 0.15)
				)
				(justify right top)
			)
		)
		(fp_text user "Author: Antmicro"
			(at -0.939 3.399 0)
			(layer "F.Fab")
			(effects
				(font
					(size 0.7 0.7)
					(thickness 0.15)
				)
				(justify right top)
			)
		)
		(pad "1" smd roundrect
			(at -0.48 0 180)
			(size 0.59 0.64)
			(layers "F.Cu" "F.Mask" "F.Paste")
			(roundrect_rratio 0.25)
			(net 91 "/USB Hub/USBC4_CONN_TX1_N")
			(pintype "passive")
		)
		(pad "2" smd roundrect
			(at 0.48 0 180)
			(size 0.59 0.64)
			(layers "F.Cu" "F.Mask" "F.Paste")
			(roundrect_rratio 0.25)
			(net 44 "/USB Hub/USBC4_TX_{1}-")
			(pintype "passive")
		)
	)
	(footprint "antmicro-footprints:C_0603_1608Metric_EIA"
		(layer "F.Cu")
		(at 141.82 56.3 180)
		(descr "Capacitor SMD 0603, IPC-7351 Density Level A")
		(tags "Capacitor 0603")
		(property "Reference" "C62"
			(at -1.05 -0.73 0)
			(layer "F.SilkS")
			(effects
				(font
					(size 0.7 0.7)
					(thickness 0.15)
				)
				(justify right top)
			)
		)
		(property "Value" "C_22u_16V_0603"
			(at -1.42757 1.770288 0)
			(layer "F.Fab")
			(effects
				(font
					(size 0.7 0.7)
					(thickness 0.15)
				)
				(justify right top)
			)
		)
		(property "Datasheet" "https://product.samsungsem.com/mlcc/CL10A226MO7JZN.do"
			(at 0 0 0)
			(layer "F.Fab")
			(hide yes)
			(effects
				(font
					(size 1.27 1.27)
					(thickness 0.15)
				)
			)
		)
		(property "Description" "SMD Multilayer Ceramic Capacitor"
			(at 0 0 0)
			(layer "F.Fab")
			(hide yes)
			(effects
				(font
					(size 1.27 1.27)
					(thickness 0.15)
				)
			)
		)
		(property "Manufacturer" "Samsung Electro-Mechanics"
			(at 0 0 180)
			(unlocked yes)
			(layer "F.Fab")
			(hide yes)
			(effects
				(font
					(size 1 1)
					(thickness 0.15)
				)
			)
		)
		(property "MPN" "CL10A226MO7JZNC"
			(at 0 0 180)
			(unlocked yes)
			(layer "F.Fab")
			(hide yes)
			(effects
				(font
					(size 1 1)
					(thickness 0.15)
				)
			)
		)
		(property "Val" "22u"
			(at 0 0 180)
			(unlocked yes)
			(layer "F.Fab")
			(hide yes)
			(effects
				(font
					(size 1 1)
					(thickness 0.15)
				)
			)
		)
		(property "License" "Apache-2.0"
			(at 0 0 180)
			(unlocked yes)
			(layer "F.Fab")
			(hide yes)
			(effects
				(font
					(size 1 1)
					(thickness 0.15)
				)
			)
		)
		(property "Author" "Antmicro"
			(at 0 0 180)
			(unlocked yes)
			(layer "F.Fab")
			(hide yes)
			(effects
				(font
					(size 1 1)
					(thickness 0.15)
				)
			)
		)
		(property "Voltage" "16V"
			(at 0 0 180)
			(unlocked yes)
			(layer "F.Fab")
			(hide yes)
			(effects
				(font
					(size 1 1)
					(thickness 0.15)
				)
			)
		)
		(property "Dielectric" ""
			(at 0 0 180)
			(unlocked yes)
			(layer "F.Fab")
			(hide yes)
			(effects
				(font
					(size 1 1)
					(thickness 0.15)
				)
			)
		)
		(sheetname "/Power/")
		(sheetfile "power.kicad_sch")
		(attr smd)
		(fp_line
			(start -0.15 0.55)
			(end 0.15 0.55)
			(stroke
				(width 0.15)
				(type solid)
			)
			(layer "F.SilkS")
		)
		(fp_line
			(start -0.15 -0.55)
			(end 0.15 -0.55)
			(stroke
				(width 0.15)
				(type solid)
			)
			(layer "F.SilkS")
		)
		(fp_poly
			(pts
				(xy -1.25 -0.65) (xy 1.25 -0.65) (xy 1.25 0.65) (xy -1.25 0.65)
			)
			(stroke
				(width 0.05)
				(type solid)
			)
			(fill no)
			(layer "F.CrtYd")
		)
		(fp_poly
			(pts
				(xy -0.799999 -0.45) (xy 0.799999 -0.45) (xy 0.799999 0.45) (xy -0.799999 0.45)
			)
			(stroke
				(width 0.15)
				(type solid)
			)
			(fill no)
			(layer "F.Fab")
		)
		(fp_text user "License: Apache-2.0"
			(at -1.682 5.895 0)
			(layer "F.Fab")
			(effects
				(font
					(size 0.7 0.7)
					(thickness 0.15)
				)
				(justify right top)
			)
		)
		(fp_text user "${REFERENCE}"
			(at -1.682001 3.895 0)
			(layer "F.Fab")
			(effects
				(font
					(size 0.7 0.7)
					(thickness 0.15)
				)
				(justify right top)
			)
		)
		(fp_text user "Author: Antmicro"
			(at -1.682 4.894 0)
			(layer "F.Fab")
			(effects
				(font
					(size 0.7 0.7)
					(thickness 0.15)
				)
				(justify right top)
			)
		)
		(pad "1" smd roundrect
			(at -0.7 0 180)
			(size 0.8 1.1)
			(layers "F.Cu" "F.Mask" "F.Paste")
			(roundrect_rratio 0.2)
			(net 1 "GND")
			(pintype "passive")
		)
		(pad "2" smd roundrect
			(at 0.7 0 180)
			(size 0.8 1.1)
			(layers "F.Cu" "F.Mask" "F.Paste")
			(roundrect_rratio 0.2)
			(net 491 "+5V_AON")
			(pintype "passive")
		)
	)
	(footprint "antmicro-footprints:TP_SMD_0.75mm"
		(layer "F.Cu")
		(at 182 57.16 90)
		(property "Reference" "TP61"
			(at -1.99 -0.68625 90)
			(layer "F.SilkS")
			(hide yes)
			(effects
				(font
					(size 0.7 0.7)
					(thickness 0.15)
				)
				(justify left bottom)
			)
		)
		(property "Value" "TP_0.75mm_SMD"
			(at 0 1.2 90)
			(layer "F.Fab")
			(effects
				(font
					(size 0.7 0.7)
					(thickness 0.15)
				)
				(justify left bottom)
			)
		)
		(property "Description" "SMT test point"
			(at 0 0 90)
			(layer "F.Fab")
			(hide yes)
			(effects
				(font
					(size 1.27 1.27)
					(thickness 0.15)
				)
			)
		)
		(property "MPN" ""
			(at 0 0 90)
			(unlocked yes)
			(layer "F.Fab")
			(hide yes)
			(effects
				(font
					(size 1 1)
					(thickness 0.15)
				)
			)
		)
		(property "Manufacturer" ""
			(at 0 0 90)
			(unlocked yes)
			(layer "F.Fab")
			(hide yes)
			(effects
				(font
					(size 1 1)
					(thickness 0.15)
				)
			)
		)
		(property "Author" "Antmicro"
			(at 0 0 90)
			(unlocked yes)
			(layer "F.Fab")
			(hide yes)
			(effects
				(font
					(size 1 1)
					(thickness 0.15)
				)
			)
		)
		(property "License" "Apache-2.0"
			(at 0 0 90)
			(unlocked yes)
			(layer "F.Fab")
			(hide yes)
			(effects
				(font
					(size 1 1)
					(thickness 0.15)
				)
			)
		)
		(sheetname "/Power/")
		(sheetfile "power.kicad_sch")
		(attr exclude_from_pos_files exclude_from_bom)
		(fp_circle
			(center 0 0)
			(end 0.475 0)
			(stroke
				(width 0.05)
				(type default)
			)
			(fill no)
			(layer "F.CrtYd")
		)
		(fp_text user "Author: Antmicro"
			(at -0.4 3.901 90)
			(layer "F.Fab")
			(effects
				(font
					(size 0.7 0.7)
					(thickness 0.15)
				)
				(justify left bottom)
			)
		)
		(fp_text user "License: Apache-2.0"
			(at -0.4 5.101 90)
			(layer "F.Fab")
			(effects
				(font
					(size 0.7 0.7)
					(thickness 0.15)
				)
				(justify left bottom)
			)
		)
		(fp_text user "${REFERENCE}"
			(at -0.4 2.7 90)
			(layer "F.Fab")
			(effects
				(font
					(size 0.7 0.7)
					(thickness 0.15)
				)
				(justify left bottom)
			)
		)
		(pad "1" smd circle
			(at 0 0 90)
			(size 0.75 0.75)
			(layers "F.Cu" "F.Mask")
			(net 904 "+20V")
			(pinfunction "1")
			(pintype "passive")
		)
	)
)
